(kicad_pcb
	(version 20260206)
	(generator "pcbnew")
	(generator_version "10.0")
	(general
		(thickness 1.6)
		(legacy_teardrops no)
	)
	(paper "A4")
	(title_block
		(title "04192023_DAF0TMB3IC0_F0TG_MB_C_brd_V02_OCP.brd")
		(comment 1 "Grand Teton / footprints 1902-1908 of 8354")
	)
	(layers
		(0 "F.Cu" signal "TOP")
		(4 "In1.Cu" signal "GND")
		(6 "In2.Cu" signal "IN1")
		(8 "In3.Cu" signal "GND1")
		(10 "In4.Cu" signal "IN2")
		(12 "In5.Cu" signal "GND2")
		(14 "In6.Cu" signal "IN3")
		(16 "In7.Cu" signal "GND3")
		(18 "In8.Cu" signal "VCC")
		(20 "In9.Cu" signal "VCC1")
		(22 "In10.Cu" signal "GND4")
		(24 "In11.Cu" signal "IN4")
		(26 "In12.Cu" signal "GND5")
		(28 "In13.Cu" signal "IN5")
		(30 "In14.Cu" signal "GND6")
		(32 "In15.Cu" signal "IN6")
		(34 "In16.Cu" signal "GND7")
		(2 "B.Cu" signal "BOTTOM")
		(9 "F.Adhes" user "F.Adhesive")
		(11 "B.Adhes" user "B.Adhesive")
		(13 "F.Paste" user "Package Geometry/Pastemask Top")
		(15 "B.Paste" user "Package Geometry/Pastemask Bottom")
		(5 "F.SilkS" user "Ref Des/Silkscreen Top")
		(7 "B.SilkS" user "Ref Des/Silkscreen Bottom")
		(1 "F.Mask" user "Board Geometry/Soldermask Top")
		(3 "B.Mask" user "Board Geometry/Soldermask Bottom")
		(17 "Dwgs.User" user "User.Drawings")
		(19 "Cmts.User" user "User.Comments")
		(21 "Eco1.User" user "User.Eco1")
		(23 "Eco2.User" user "User.Eco2")
		(25 "Edge.Cuts" user "Board Geometry/Outline")
		(27 "Margin" user)
		(31 "F.CrtYd" user "Package Geometry/Place Bound Top")
		(29 "B.CrtYd" user "Package Geometry/Place Bound Bottom")
		(35 "F.Fab" user "Ref Des/Assembly Top")
		(33 "B.Fab" user "Ref Des/Assembly Bottom")
	)
	(footprint ""
		(layer "F.Cu")
		(at 416.856418 -366.325912)
		(property "Reference" "R118"
			(at 0 0 0)
			(layer "F.SilkS")
			(hide yes)
			(effects
				(font
					(size 1.27 1.27)
				)
			)
		)
		(property "Value" ""
			(at 0 0 0)
			(layer "F.Fab")
			(effects
				(font
					(size 1.27 1.27)
				)
			)
		)
		(duplicate_pad_numbers_are_jumpers no)
		(fp_line
			(start -0.7874 -0.4064)
			(end 0.7874 -0.4064)
			(stroke
				(width 0.1524)
				(type default)
			)
			(layer "F.SilkS")
		)
		(fp_line
			(start -0.7874 0.4064)
			(end -0.7874 -0.4064)
			(stroke
				(width 0.1524)
				(type default)
			)
			(layer "F.SilkS")
		)
		(fp_line
			(start 0.7874 -0.4064)
			(end 0.7874 0.4064)
			(stroke
				(width 0.1524)
				(type default)
			)
			(layer "F.SilkS")
		)
		(fp_line
			(start 0.7874 0.4064)
			(end -0.7874 0.4064)
			(stroke
				(width 0.1524)
				(type default)
			)
			(layer "F.SilkS")
		)
		(fp_line
			(start -0.67945 -0.305054)
			(end -0.12065 -0.305054)
			(stroke
				(width 0.1)
				(type default)
			)
			(layer "F.Fab")
		)
		(fp_line
			(start -0.67945 0.3048)
			(end -0.67945 -0.305054)
			(stroke
				(width 0.1)
				(type default)
			)
			(layer "F.Fab")
		)
		(fp_line
			(start -0.12065 -0.305054)
			(end -0.12065 -0.2794)
			(stroke
				(width 0.1)
				(type default)
			)
			(layer "F.Fab")
		)
		(fp_line
			(start -0.12065 -0.2794)
			(end 0.12065 -0.2794)
			(stroke
				(width 0.1)
				(type default)
			)
			(layer "F.Fab")
		)
		(fp_line
			(start -0.12065 0.2794)
			(end -0.12065 0.3048)
			(stroke
				(width 0.1)
				(type default)
			)
			(layer "F.Fab")
		)
		(fp_line
			(start -0.12065 0.3048)
			(end -0.67945 0.3048)
			(stroke
				(width 0.1)
				(type default)
			)
			(layer "F.Fab")
		)
		(fp_line
			(start 0.120396 0.2794)
			(end -0.12065 0.2794)
			(stroke
				(width 0.1)
				(type default)
			)
			(layer "F.Fab")
		)
		(fp_line
			(start 0.120396 0.3048)
			(end 0.120396 0.2794)
			(stroke
				(width 0.1)
				(type default)
			)
			(layer "F.Fab")
		)
		(fp_line
			(start 0.12065 -0.3048)
			(end 0.67945 -0.3048)
			(stroke
				(width 0.1)
				(type default)
			)
			(layer "F.Fab")
		)
		(fp_line
			(start 0.12065 -0.2794)
			(end 0.12065 -0.3048)
			(stroke
				(width 0.1)
				(type default)
			)
			(layer "F.Fab")
		)
		(fp_line
			(start 0.67945 -0.3048)
			(end 0.67945 0.3048)
			(stroke
				(width 0.1)
				(type default)
			)
			(layer "F.Fab")
		)
		(fp_line
			(start 0.67945 0.3048)
			(end 0.120396 0.3048)
			(stroke
				(width 0.1)
				(type default)
			)
			(layer "F.Fab")
		)
		(pad "1" smd circle
			(at -0.40005 0)
			(size 0 0)
			(layers "F.Cu" "F.Mask" "F.Paste")
			(net "SMB_SCM_2_R6_SCL")
		)
		(pad "2" smd circle
			(at 0.40005 0)
			(size 0 0)
			(layers "F.Cu" "F.Mask" "F.Paste")
			(net "PVDD11_S3_P0_PMSCL_R")
		)
	)
	(footprint ""
		(layer "F.Cu")
		(at 166.3192 -432.4096 180)
		(property "Reference" "R2707"
			(at 0 0 180)
			(layer "F.SilkS")
			(hide yes)
			(effects
				(font
					(size 1.27 1.27)
				)
			)
		)
		(property "Value" ""
			(at 0 0 180)
			(layer "F.Fab")
			(effects
				(font
					(size 1.27 1.27)
				)
			)
		)
		(duplicate_pad_numbers_are_jumpers no)
		(fp_line
			(start 0.7874 0.4064)
			(end -0.7874 0.4064)
			(stroke
				(width 0.1524)
				(type default)
			)
			(layer "F.SilkS")
		)
		(fp_line
			(start 0.7874 -0.4064)
			(end 0.7874 0.4064)
			(stroke
				(width 0.1524)
				(type default)
			)
			(layer "F.SilkS")
		)
		(fp_line
			(start -0.7874 0.4064)
			(end -0.7874 -0.4064)
			(stroke
				(width 0.1524)
				(type default)
			)
			(layer "F.SilkS")
		)
		(fp_line
			(start -0.7874 -0.4064)
			(end 0.7874 -0.4064)
			(stroke
				(width 0.1524)
				(type default)
			)
			(layer "F.SilkS")
		)
		(fp_line
			(start 0.67945 0.3048)
			(end 0.120396 0.3048)
			(stroke
				(width 0.1)
				(type default)
			)
			(layer "F.Fab")
		)
		(fp_line
			(start 0.67945 -0.3048)
			(end 0.67945 0.3048)
			(stroke
				(width 0.1)
				(type default)
			)
			(layer "F.Fab")
		)
		(fp_line
			(start 0.12065 -0.2794)
			(end 0.12065 -0.3048)
			(stroke
				(width 0.1)
				(type default)
			)
			(layer "F.Fab")
		)
		(fp_line
			(start 0.12065 -0.3048)
			(end 0.67945 -0.3048)
			(stroke
				(width 0.1)
				(type default)
			)
			(layer "F.Fab")
		)
		(fp_line
			(start 0.120396 0.3048)
			(end 0.120396 0.2794)
			(stroke
				(width 0.1)
				(type default)
			)
			(layer "F.Fab")
		)
		(fp_line
			(start 0.120396 0.2794)
			(end -0.12065 0.2794)
			(stroke
				(width 0.1)
				(type default)
			)
			(layer "F.Fab")
		)
		(fp_line
			(start -0.12065 0.3048)
			(end -0.67945 0.3048)
			(stroke
				(width 0.1)
				(type default)
			)
			(layer "F.Fab")
		)
		(fp_line
			(start -0.12065 0.2794)
			(end -0.12065 0.3048)
			(stroke
				(width 0.1)
				(type default)
			)
			(layer "F.Fab")
		)
		(fp_line
			(start -0.12065 -0.2794)
			(end 0.12065 -0.2794)
			(stroke
				(width 0.1)
				(type default)
			)
			(layer "F.Fab")
		)
		(fp_line
			(start -0.12065 -0.305054)
			(end -0.12065 -0.2794)
			(stroke
				(width 0.1)
				(type default)
			)
			(layer "F.Fab")
		)
		(fp_line
			(start -0.67945 0.3048)
			(end -0.67945 -0.305054)
			(stroke
				(width 0.1)
				(type default)
			)
			(layer "F.Fab")
		)
		(fp_line
			(start -0.67945 -0.305054)
			(end -0.12065 -0.305054)
			(stroke
				(width 0.1)
				(type default)
			)
			(layer "F.Fab")
		)
		(pad "1" smd circle
			(at -0.40005 0 180)
			(size 0 0)
			(layers "F.Cu" "F.Mask" "F.Paste")
			(net "SMB_BMC_SWB_EN")
		)
		(pad "2" smd circle
			(at 0.40005 0 180)
			(size 0 0)
			(layers "F.Cu" "F.Mask" "F.Paste")
			(net "SMB_BMC_SWB_EN_R")
		)
	)
	(footprint ""
		(layer "F.Cu")
		(at 378.002292 -383.88163 -90)
		(property "Reference" "C887"
			(at 0 0 270)
			(layer "F.SilkS")
			(hide yes)
			(effects
				(font
					(size 1.27 1.27)
				)
			)
		)
		(property "Value" ""
			(at 0 0 270)
			(layer "F.Fab")
			(effects
				(font
					(size 1.27 1.27)
				)
			)
		)
		(duplicate_pad_numbers_are_jumpers no)
		(fp_line
			(start -0.299974 0.150114)
			(end -0.299974 -0.150114)
			(stroke
				(width 0.1)
				(type default)
			)
			(layer "F.Fab")
		)
		(fp_line
			(start 0.299974 0.150114)
			(end -0.299974 0.150114)
			(stroke
				(width 0.1)
				(type default)
			)
			(layer "F.Fab")
		)
		(fp_line
			(start -0.299974 -0.150114)
			(end 0.299974 -0.150114)
			(stroke
				(width 0.1)
				(type default)
			)
			(layer "F.Fab")
		)
		(fp_line
			(start 0.299974 -0.150114)
			(end 0.299974 0.150114)
			(stroke
				(width 0.1)
				(type default)
			)
			(layer "F.Fab")
		)
		(pad "1" smd rect
			(at -0.2667 0 270)
			(size 0.3048 0.381)
			(layers "F.Cu" "F.Mask" "F.Paste")
			(net "P5E_CPU0_P3_TX_C_DP<7>")
		)
		(pad "2" smd rect
			(at 0.2667 0 270)
			(size 0.3048 0.381)
			(layers "F.Cu" "F.Mask" "F.Paste")
			(net "P5E_CPU0_P3_TX_DP<7>")
		)
	)
	(footprint ""
		(layer "F.Cu")
		(at 172.54347 -418.551868 180)
		(property "Reference" "R9007"
			(at 0 0 180)
			(layer "F.SilkS")
			(hide yes)
			(effects
				(font
					(size 1.27 1.27)
				)
			)
		)
		(property "Value" ""
			(at 0 0 180)
			(layer "F.Fab")
			(effects
				(font
					(size 1.27 1.27)
				)
			)
		)
		(duplicate_pad_numbers_are_jumpers no)
		(fp_line
			(start 0.7874 0.4064)
			(end -0.7874 0.4064)
			(stroke
				(width 0.1524)
				(type default)
			)
			(layer "F.SilkS")
		)
		(fp_line
			(start 0.7874 -0.4064)
			(end 0.7874 0.4064)
			(stroke
				(width 0.1524)
				(type default)
			)
			(layer "F.SilkS")
		)
		(fp_line
			(start -0.7874 0.4064)
			(end -0.7874 -0.4064)
			(stroke
				(width 0.1524)
				(type default)
			)
			(layer "F.SilkS")
		)
		(fp_line
			(start -0.7874 -0.4064)
			(end 0.7874 -0.4064)
			(stroke
				(width 0.1524)
				(type default)
			)
			(layer "F.SilkS")
		)
		(fp_line
			(start 0.67945 0.3048)
			(end 0.120396 0.3048)
			(stroke
				(width 0.1)
				(type default)
			)
			(layer "F.Fab")
		)
		(fp_line
			(start 0.67945 -0.3048)
			(end 0.67945 0.3048)
			(stroke
				(width 0.1)
				(type default)
			)
			(layer "F.Fab")
		)
		(fp_line
			(start 0.12065 -0.2794)
			(end 0.12065 -0.3048)
			(stroke
				(width 0.1)
				(type default)
			)
			(layer "F.Fab")
		)
		(fp_line
			(start 0.12065 -0.3048)
			(end 0.67945 -0.3048)
			(stroke
				(width 0.1)
				(type default)
			)
			(layer "F.Fab")
		)
		(fp_line
			(start 0.120396 0.3048)
			(end 0.120396 0.2794)
			(stroke
				(width 0.1)
				(type default)
			)
			(layer "F.Fab")
		)
		(fp_line
			(start 0.120396 0.2794)
			(end -0.12065 0.2794)
			(stroke
				(width 0.1)
				(type default)
			)
			(layer "F.Fab")
		)
		(fp_line
			(start -0.12065 0.3048)
			(end -0.67945 0.3048)
			(stroke
				(width 0.1)
				(type default)
			)
			(layer "F.Fab")
		)
		(fp_line
			(start -0.12065 0.2794)
			(end -0.12065 0.3048)
			(stroke
				(width 0.1)
				(type default)
			)
			(layer "F.Fab")
		)
		(fp_line
			(start -0.12065 -0.2794)
			(end 0.12065 -0.2794)
			(stroke
				(width 0.1)
				(type default)
			)
			(layer "F.Fab")
		)
		(fp_line
			(start -0.12065 -0.305054)
			(end -0.12065 -0.2794)
			(stroke
				(width 0.1)
				(type default)
			)
			(layer "F.Fab")
		)
		(fp_line
			(start -0.67945 0.3048)
			(end -0.67945 -0.305054)
			(stroke
				(width 0.1)
				(type default)
			)
			(layer "F.Fab")
		)
		(fp_line
			(start -0.67945 -0.305054)
			(end -0.12065 -0.305054)
			(stroke
				(width 0.1)
				(type default)
			)
			(layer "F.Fab")
		)
		(pad "1" smd circle
			(at -0.40005 0 180)
			(size 0 0)
			(layers "F.Cu" "F.Mask" "F.Paste")
			(net "PRSNT_CABLE_SWB_B2_N")
		)
		(pad "2" smd circle
			(at 0.40005 0 180)
			(size 0 0)
			(layers "F.Cu" "F.Mask" "F.Paste")
			(net "GND")
		)
	)
	(footprint ""
		(layer "F.Cu")
		(at 412.472886 -72.832468)
		(property "Reference" "R3263"
			(at 0 0 0)
			(layer "F.SilkS")
			(hide yes)
			(effects
				(font
					(size 1.27 1.27)
				)
			)
		)
		(property "Value" ""
			(at 0 0 0)
			(layer "F.Fab")
			(effects
				(font
					(size 1.27 1.27)
				)
			)
		)
		(duplicate_pad_numbers_are_jumpers no)
		(fp_line
			(start -0.7874 -0.4064)
			(end 0.7874 -0.4064)
			(stroke
				(width 0.1524)
				(type default)
			)
			(layer "F.SilkS")
		)
		(fp_line
			(start -0.7874 0.4064)
			(end -0.7874 -0.4064)
			(stroke
				(width 0.1524)
				(type default)
			)
			(layer "F.SilkS")
		)
		(fp_line
			(start 0.7874 -0.4064)
			(end 0.7874 0.4064)
			(stroke
				(width 0.1524)
				(type default)
			)
			(layer "F.SilkS")
		)
		(fp_line
			(start 0.7874 0.4064)
			(end -0.7874 0.4064)
			(stroke
				(width 0.1524)
				(type default)
			)
			(layer "F.SilkS")
		)
		(fp_line
			(start -0.67945 -0.305054)
			(end -0.12065 -0.305054)
			(stroke
				(width 0.1)
				(type default)
			)
			(layer "F.Fab")
		)
		(fp_line
			(start -0.67945 0.3048)
			(end -0.67945 -0.305054)
			(stroke
				(width 0.1)
				(type default)
			)
			(layer "F.Fab")
		)
		(fp_line
			(start -0.12065 -0.305054)
			(end -0.12065 -0.2794)
			(stroke
				(width 0.1)
				(type default)
			)
			(layer "F.Fab")
		)
		(fp_line
			(start -0.12065 -0.2794)
			(end 0.12065 -0.2794)
			(stroke
				(width 0.1)
				(type default)
			)
			(layer "F.Fab")
		)
		(fp_line
			(start -0.12065 0.2794)
			(end -0.12065 0.3048)
			(stroke
				(width 0.1)
				(type default)
			)
			(layer "F.Fab")
		)
		(fp_line
			(start -0.12065 0.3048)
			(end -0.67945 0.3048)
			(stroke
				(width 0.1)
				(type default)
			)
			(layer "F.Fab")
		)
		(fp_line
			(start 0.120396 0.2794)
			(end -0.12065 0.2794)
			(stroke
				(width 0.1)
				(type default)
			)
			(layer "F.Fab")
		)
		(fp_line
			(start 0.120396 0.3048)
			(end 0.120396 0.2794)
			(stroke
				(width 0.1)
				(type default)
			)
			(layer "F.Fab")
		)
		(fp_line
			(start 0.12065 -0.3048)
			(end 0.67945 -0.3048)
			(stroke
				(width 0.1)
				(type default)
			)
			(layer "F.Fab")
		)
		(fp_line
			(start 0.12065 -0.2794)
			(end 0.12065 -0.3048)
			(stroke
				(width 0.1)
				(type default)
			)
			(layer "F.Fab")
		)
		(fp_line
			(start 0.67945 -0.3048)
			(end 0.67945 0.3048)
			(stroke
				(width 0.1)
				(type default)
			)
			(layer "F.Fab")
		)
		(fp_line
			(start 0.67945 0.3048)
			(end 0.120396 0.3048)
			(stroke
				(width 0.1)
				(type default)
			)
			(layer "F.Fab")
		)
		(pad "1" smd circle
			(at -0.40005 0)
			(size 0 0)
			(layers "F.Cu" "F.Mask" "F.Paste")
			(net "HP_LVC3_OCP_V3_1_R_EN")
		)
		(pad "2" smd circle
			(at 0.40005 0)
			(size 0 0)
			(layers "F.Cu" "F.Mask" "F.Paste")
			(net "P3V3_OCP_SFF_EN_R")
		)
	)
	(footprint ""
		(layer "F.Cu")
		(at 14.886178 -107.631484 180)
		(property "Reference" "R4482"
			(at 0 0 180)
			(layer "F.SilkS")
			(hide yes)
			(effects
				(font
					(size 1.27 1.27)
				)
			)
		)
		(property "Value" ""
			(at 0 0 180)
			(layer "F.Fab")
			(effects
				(font
					(size 1.27 1.27)
				)
			)
		)
		(duplicate_pad_numbers_are_jumpers no)
		(fp_line
			(start 0.7874 0.4064)
			(end -0.7874 0.4064)
			(stroke
				(width 0.1524)
				(type default)
			)
			(layer "F.SilkS")
		)
		(fp_line
			(start 0.7874 -0.4064)
			(end 0.7874 0.4064)
			(stroke
				(width 0.1524)
				(type default)
			)
			(layer "F.SilkS")
		)
		(fp_line
			(start -0.7874 0.4064)
			(end -0.7874 -0.4064)
			(stroke
				(width 0.1524)
				(type default)
			)
			(layer "F.SilkS")
		)
		(fp_line
			(start -0.7874 -0.4064)
			(end 0.7874 -0.4064)
			(stroke
				(width 0.1524)
				(type default)
			)
			(layer "F.SilkS")
		)
		(fp_line
			(start 0.67945 0.3048)
			(end 0.120396 0.3048)
			(stroke
				(width 0.1)
				(type default)
			)
			(layer "F.Fab")
		)
		(fp_line
			(start 0.67945 -0.3048)
			(end 0.67945 0.3048)
			(stroke
				(width 0.1)
				(type default)
			)
			(layer "F.Fab")
		)
		(fp_line
			(start 0.12065 -0.2794)
			(end 0.12065 -0.3048)
			(stroke
				(width 0.1)
				(type default)
			)
			(layer "F.Fab")
		)
		(fp_line
			(start 0.12065 -0.3048)
			(end 0.67945 -0.3048)
			(stroke
				(width 0.1)
				(type default)
			)
			(layer "F.Fab")
		)
		(fp_line
			(start 0.120396 0.3048)
			(end 0.120396 0.2794)
			(stroke
				(width 0.1)
				(type default)
			)
			(layer "F.Fab")
		)
		(fp_line
			(start 0.120396 0.2794)
			(end -0.12065 0.2794)
			(stroke
				(width 0.1)
				(type default)
			)
			(layer "F.Fab")
		)
		(fp_line
			(start -0.12065 0.3048)
			(end -0.67945 0.3048)
			(stroke
				(width 0.1)
				(type default)
			)
			(layer "F.Fab")
		)
		(fp_line
			(start -0.12065 0.2794)
			(end -0.12065 0.3048)
			(stroke
				(width 0.1)
				(type default)
			)
			(layer "F.Fab")
		)
		(fp_line
			(start -0.12065 -0.2794)
			(end 0.12065 -0.2794)
			(stroke
				(width 0.1)
				(type default)
			)
			(layer "F.Fab")
		)
		(fp_line
			(start -0.12065 -0.305054)
			(end -0.12065 -0.2794)
			(stroke
				(width 0.1)
				(type default)
			)
			(layer "F.Fab")
		)
		(fp_line
			(start -0.67945 0.3048)
			(end -0.67945 -0.305054)
			(stroke
				(width 0.1)
				(type default)
			)
			(layer "F.Fab")
		)
		(fp_line
			(start -0.67945 -0.305054)
			(end -0.12065 -0.305054)
			(stroke
				(width 0.1)
				(type default)
			)
			(layer "F.Fab")
		)
		(pad "1" smd circle
			(at -0.40005 0 180)
			(size 0 0)
			(layers "F.Cu" "F.Mask" "F.Paste")
			(net "USB2_HOST_BMC_B_BUF_DP")
		)
		(pad "2" smd circle
			(at 0.40005 0 180)
			(size 0 0)
			(layers "F.Cu" "F.Mask" "F.Paste")
			(net "GND")
		)
	)
	(footprint ""
		(layer "F.Cu")
		(at 280.025348 -344.982038 90)
		(property "Reference" "PR379"
			(at 0 0 90)
			(layer "F.SilkS")
			(hide yes)
			(effects
				(font
					(size 1.27 1.27)
				)
			)
		)
		(property "Value" ""
			(at 0 0 90)
			(layer "F.Fab")
			(effects
				(font
					(size 1.27 1.27)
				)
			)
		)
		(duplicate_pad_numbers_are_jumpers no)
		(fp_line
			(start 0.7874 -0.4064)
			(end 0.7874 0.4064)
			(stroke
				(width 0.1524)
				(type default)
			)
			(layer "F.SilkS")
		)
		(fp_line
			(start -0.7874 -0.4064)
			(end 0.7874 -0.4064)
			(stroke
				(width 0.1524)
				(type default)
			)
			(layer "F.SilkS")
		)
		(fp_line
			(start 0.7874 0.4064)
			(end -0.7874 0.4064)
			(stroke
				(width 0.1524)
				(type default)
			)
			(layer "F.SilkS")
		)
		(fp_line
			(start -0.7874 0.4064)
			(end -0.7874 -0.4064)
			(stroke
				(width 0.1524)
				(type default)
			)
			(layer "F.SilkS")
		)
		(fp_line
			(start -0.12065 -0.305054)
			(end -0.12065 -0.2794)
			(stroke
				(width 0.1)
				(type default)
			)
			(layer "F.Fab")
		)
		(fp_line
			(start -0.67945 -0.305054)
			(end -0.12065 -0.305054)
			(stroke
				(width 0.1)
				(type default)
			)
			(layer "F.Fab")
		)
		(fp_line
			(start 0.67945 -0.3048)
			(end 0.67945 0.3048)
			(stroke
				(width 0.1)
				(type default)
			)
			(layer "F.Fab")
		)
		(fp_line
			(start 0.12065 -0.3048)
			(end 0.67945 -0.3048)
			(stroke
				(width 0.1)
				(type default)
			)
			(layer "F.Fab")
		)
		(fp_line
			(start 0.12065 -0.2794)
			(end 0.12065 -0.3048)
			(stroke
				(width 0.1)
				(type default)
			)
			(layer "F.Fab")
		)
		(fp_line
			(start -0.12065 -0.2794)
			(end 0.12065 -0.2794)
			(stroke
				(width 0.1)
				(type default)
			)
			(layer "F.Fab")
		)
		(fp_line
			(start 0.120396 0.2794)
			(end -0.12065 0.2794)
			(stroke
				(width 0.1)
				(type default)
			)
			(layer "F.Fab")
		)
		(fp_line
			(start -0.12065 0.2794)
			(end -0.12065 0.3048)
			(stroke
				(width 0.1)
				(type default)
			)
			(layer "F.Fab")
		)
		(fp_line
			(start 0.67945 0.3048)
			(end 0.120396 0.3048)
			(stroke
				(width 0.1)
				(type default)
			)
			(layer "F.Fab")
		)
		(fp_line
			(start 0.120396 0.3048)
			(end 0.120396 0.2794)
			(stroke
				(width 0.1)
				(type default)
			)
			(layer "F.Fab")
		)
		(fp_line
			(start -0.12065 0.3048)
			(end -0.67945 0.3048)
			(stroke
				(width 0.1)
				(type default)
			)
			(layer "F.Fab")
		)
		(fp_line
			(start -0.67945 0.3048)
			(end -0.67945 -0.305054)
			(stroke
				(width 0.1)
				(type default)
			)
			(layer "F.Fab")
		)
		(pad "1" smd circle
			(at -0.40005 0 90)
			(size 0 0)
			(layers "F.Cu" "F.Mask" "F.Paste")
			(net "SW_PVDDIO_P0_SW3_RC")
		)
		(pad "2" smd circle
			(at 0.40005 0 90)
			(size 0 0)
			(layers "F.Cu" "F.Mask" "F.Paste")
			(net "GND")
		)
	)
)
